# S9S_MB_2U (Grand Teton) — schematic netlist excerpt (pin names and nets, part order shuffled) for the footprints in the layout excerpt that follows; sources: Cadence DE-HDL packaged netlist, KiCad conversion of 03242023_DA0F0TMBIJ0_F0T_Motherboard_J_brd_V01_OCP.brd

PR102  Q_RES  2.2 1% CHIP  pkg 0402LF  page 275 : A = PVCCFA_EHV_CPU0_PVCC ; B = PVCCINFAON_CPU0_VDD2
PC282_P0_4  Q_CAP  22UF 16V 20% X6S  pkg C0805  page 268 : A = SW_P12V_PVCCIN_CPU0_FLT ; B = GND
R1526  Q_RES  33.2 1% CHIP  pkg 0402LF  page 241 : A = SMB_HOST_3V3AUX_SDA_R ; B = SMB_HOST_CLK_3V3AUX_SDA

(kicad_pcb
	(version 20260206)
	(generator "pcbnew")
	(generator_version "10.0")
	(general
		(thickness 1.6)
		(legacy_teardrops no)
	)
	(paper "A4")
	(title_block
		(title "03242023_DA0F0TMBIJ0_F0T_Motherboard_J_brd_V01_OCP.brd")
		(comment 1 "Grand Teton / footprints 5090-5092 of 6105")
	)
	(layers
		(0 "F.Cu" signal "TOP")
		(4 "In1.Cu" signal "GND")
		(6 "In2.Cu" signal "IN1")
		(8 "In3.Cu" signal "GND1")
		(10 "In4.Cu" signal "IN2")
		(12 "In5.Cu" signal "GND2")
		(14 "In6.Cu" signal "IN3")
		(16 "In7.Cu" signal "GND3")
		(18 "In8.Cu" signal "VCC")
		(20 "In9.Cu" signal "VCC1")
		(22 "In10.Cu" signal "GND4")
		(24 "In11.Cu" signal "IN4")
		(26 "In12.Cu" signal "GND5")
		(28 "In13.Cu" signal "IN5")
		(30 "In14.Cu" signal "GND6")
		(32 "In15.Cu" signal "IN6")
		(34 "In16.Cu" signal "GND7")
		(2 "B.Cu" signal "BOTTOM")
		(9 "F.Adhes" user "F.Adhesive")
		(11 "B.Adhes" user "B.Adhesive")
		(13 "F.Paste" user "Package Geometry/Pastemask Top")
		(15 "B.Paste" user "Package Geometry/Pastemask Bottom")
		(5 "F.SilkS" user "Ref Des/Silkscreen Top")
		(7 "B.SilkS" user "Ref Des/Silkscreen Bottom")
		(1 "F.Mask" user "Board Geometry/Soldermask Top")
		(3 "B.Mask" user "Board Geometry/Soldermask Bottom")
		(17 "Dwgs.User" user "User.Drawings")
		(19 "Cmts.User" user "User.Comments")
		(21 "Eco1.User" user "User.Eco1")
		(23 "Eco2.User" user "User.Eco2")
		(25 "Edge.Cuts" user "Board Geometry/Outline")
		(27 "Margin" user)
		(31 "F.CrtYd" user "Package Geometry/Place Bound Top")
		(29 "B.CrtYd" user "Package Geometry/Place Bound Bottom")
		(35 "F.Fab" user "Ref Des/Assembly Top")
		(33 "B.Fab" user "Ref Des/Assembly Bottom")
	)
	(footprint ""
		(layer "B.Cu")
		(at 416.996626 -181.854602 180)
		(property "Reference" "PR102"
			(at 0 0 0)
			(layer "B.SilkS")
			(hide yes)
			(effects
				(font
					(size 1.27 1.27)
				)
				(justify mirror)
			)
		)
		(property "Value" ""
			(at 0 0 0)
			(layer "B.Fab")
			(effects
				(font
					(size 1.27 1.27)
				)
				(justify mirror)
			)
		)
		(duplicate_pad_numbers_are_jumpers no)
		(fp_line
			(start 0.7874 0.4064)
			(end 0.7874 -0.4064)
			(stroke
				(width 0.1524)
				(type default)
			)
			(layer "B.SilkS")
		)
		(fp_line
			(start 0.7874 -0.4064)
			(end -0.7874 -0.4064)
			(stroke
				(width 0.1524)
				(type default)
			)
			(layer "B.SilkS")
		)
		(fp_line
			(start -0.7874 0.4064)
			(end 0.7874 0.4064)
			(stroke
				(width 0.1524)
				(type default)
			)
			(layer "B.SilkS")
		)
		(fp_line
			(start -0.7874 -0.4064)
			(end -0.7874 0.4064)
			(stroke
				(width 0.1524)
				(type default)
			)
			(layer "B.SilkS")
		)
		(fp_line
			(start 0.67945 0.3048)
			(end 0.67945 -0.305054)
			(stroke
				(width 0.1)
				(type default)
			)
			(layer "B.Fab")
		)
		(fp_line
			(start 0.67945 -0.305054)
			(end 0.12065 -0.305054)
			(stroke
				(width 0.1)
				(type default)
			)
			(layer "B.Fab")
		)
		(fp_line
			(start 0.12065 0.3048)
			(end 0.67945 0.3048)
			(stroke
				(width 0.1)
				(type default)
			)
			(layer "B.Fab")
		)
		(fp_line
			(start 0.12065 0.2794)
			(end 0.12065 0.3048)
			(stroke
				(width 0.1)
				(type default)
			)
			(layer "B.Fab")
		)
		(fp_line
			(start 0.12065 -0.2794)
			(end -0.12065 -0.2794)
			(stroke
				(width 0.1)
				(type default)
			)
			(layer "B.Fab")
		)
		(fp_line
			(start 0.12065 -0.305054)
			(end 0.12065 -0.2794)
			(stroke
				(width 0.1)
				(type default)
			)
			(layer "B.Fab")
		)
		(fp_line
			(start -0.120396 0.3048)
			(end -0.120396 0.2794)
			(stroke
				(width 0.1)
				(type default)
			)
			(layer "B.Fab")
		)
		(fp_line
			(start -0.120396 0.2794)
			(end 0.12065 0.2794)
			(stroke
				(width 0.1)
				(type default)
			)
			(layer "B.Fab")
		)
		(fp_line
			(start -0.12065 -0.2794)
			(end -0.12065 -0.3048)
			(stroke
				(width 0.1)
				(type default)
			)
			(layer "B.Fab")
		)
		(fp_line
			(start -0.12065 -0.3048)
			(end -0.67945 -0.3048)
			(stroke
				(width 0.1)
				(type default)
			)
			(layer "B.Fab")
		)
		(fp_line
			(start -0.67945 0.3048)
			(end -0.120396 0.3048)
			(stroke
				(width 0.1)
				(type default)
			)
			(layer "B.Fab")
		)
		(fp_line
			(start -0.67945 -0.3048)
			(end -0.67945 0.3048)
			(stroke
				(width 0.1)
				(type default)
			)
			(layer "B.Fab")
		)
		(pad "1" smd circle
			(at 0.40005 0)
			(size 0 0)
			(layers "B.Cu" "B.Mask" "B.Paste")
			(net "PVCCFA_EHV_CPU0_PVCC")
		)
		(pad "2" smd circle
			(at -0.40005 0)
			(size 0 0)
			(layers "B.Cu" "B.Mask" "B.Paste")
			(net "PVCCINFAON_CPU0_VDD2")
		)
	)
	(footprint ""
		(layer "B.Cu")
		(at 243.001038 -102.528624 180)
		(property "Reference" "R1526"
			(at 0 0 0)
			(layer "B.SilkS")
			(hide yes)
			(effects
				(font
					(size 1.27 1.27)
				)
				(justify mirror)
			)
		)
		(property "Value" ""
			(at 0 0 0)
			(layer "B.Fab")
			(effects
				(font
					(size 1.27 1.27)
				)
				(justify mirror)
			)
		)
		(duplicate_pad_numbers_are_jumpers no)
		(fp_line
			(start 0.7874 0.4064)
			(end 0.7874 -0.4064)
			(stroke
				(width 0.1524)
				(type default)
			)
			(layer "B.SilkS")
		)
		(fp_line
			(start 0.7874 -0.4064)
			(end -0.7874 -0.4064)
			(stroke
				(width 0.1524)
				(type default)
			)
			(layer "B.SilkS")
		)
		(fp_line
			(start -0.7874 0.4064)
			(end 0.7874 0.4064)
			(stroke
				(width 0.1524)
				(type default)
			)
			(layer "B.SilkS")
		)
		(fp_line
			(start -0.7874 -0.4064)
			(end -0.7874 0.4064)
			(stroke
				(width 0.1524)
				(type default)
			)
			(layer "B.SilkS")
		)
		(fp_line
			(start 0.67945 0.3048)
			(end 0.67945 -0.305054)
			(stroke
				(width 0.1)
				(type default)
			)
			(layer "B.Fab")
		)
		(fp_line
			(start 0.67945 -0.305054)
			(end 0.12065 -0.305054)
			(stroke
				(width 0.1)
				(type default)
			)
			(layer "B.Fab")
		)
		(fp_line
			(start 0.12065 0.3048)
			(end 0.67945 0.3048)
			(stroke
				(width 0.1)
				(type default)
			)
			(layer "B.Fab")
		)
		(fp_line
			(start 0.12065 0.2794)
			(end 0.12065 0.3048)
			(stroke
				(width 0.1)
				(type default)
			)
			(layer "B.Fab")
		)
		(fp_line
			(start 0.12065 -0.2794)
			(end -0.12065 -0.2794)
			(stroke
				(width 0.1)
				(type default)
			)
			(layer "B.Fab")
		)
		(fp_line
			(start 0.12065 -0.305054)
			(end 0.12065 -0.2794)
			(stroke
				(width 0.1)
				(type default)
			)
			(layer "B.Fab")
		)
		(fp_line
			(start -0.120396 0.3048)
			(end -0.120396 0.2794)
			(stroke
				(width 0.1)
				(type default)
			)
			(layer "B.Fab")
		)
		(fp_line
			(start -0.120396 0.2794)
			(end 0.12065 0.2794)
			(stroke
				(width 0.1)
				(type default)
			)
			(layer "B.Fab")
		)
		(fp_line
			(start -0.12065 -0.2794)
			(end -0.12065 -0.3048)
			(stroke
				(width 0.1)
				(type default)
			)
			(layer "B.Fab")
		)
		(fp_line
			(start -0.12065 -0.3048)
			(end -0.67945 -0.3048)
			(stroke
				(width 0.1)
				(type default)
			)
			(layer "B.Fab")
		)
		(fp_line
			(start -0.67945 0.3048)
			(end -0.120396 0.3048)
			(stroke
				(width 0.1)
				(type default)
			)
			(layer "B.Fab")
		)
		(fp_line
			(start -0.67945 -0.3048)
			(end -0.67945 0.3048)
			(stroke
				(width 0.1)
				(type default)
			)
			(layer "B.Fab")
		)
		(pad "1" smd circle
			(at 0.40005 0)
			(size 0 0)
			(layers "B.Cu" "B.Mask" "B.Paste")
			(net "SMB_HOST_3V3AUX_SDA_R")
		)
		(pad "2" smd circle
			(at -0.40005 0)
			(size 0 0)
			(layers "B.Cu" "B.Mask" "B.Paste")
			(net "SMB_HOST_CLK_3V3AUX_SDA")
		)
	)
	(footprint ""
		(layer "B.Cu")
		(at 370.734082 -337.546442 -90)
		(property "Reference" "PC282_P0_4"
			(at 0 0 90)
			(layer "B.SilkS")
			(hide yes)
			(effects
				(font
					(size 1.27 1.27)
				)
				(justify mirror)
			)
		)
		(property "Value" ""
			(at 0 0 90)
			(layer "B.Fab")
			(effects
				(font
					(size 1.27 1.27)
				)
				(justify mirror)
			)
		)
		(duplicate_pad_numbers_are_jumpers no)
		(fp_line
			(start -1.524 0.762)
			(end 1.524 0.762)
			(stroke
				(width 0.1524)
				(type default)
			)
			(layer "B.SilkS")
		)
		(fp_line
			(start 1.524 0.762)
			(end 1.524 -0.762)
			(stroke
				(width 0.1524)
				(type default)
			)
			(layer "B.SilkS")
		)
		(fp_line
			(start -1.524 -0.762)
			(end -1.524 0.762)
			(stroke
				(width 0.1524)
				(type default)
			)
			(layer "B.SilkS")
		)
		(fp_line
			(start 1.524 -0.762)
			(end -1.524 -0.762)
			(stroke
				(width 0.1524)
				(type default)
			)
			(layer "B.SilkS")
		)
		(fp_line
			(start -1.1049 0.724916)
			(end -1.1049 -0.724916)
			(stroke
				(width 0.1)
				(type default)
			)
			(layer "B.Fab")
		)
		(fp_line
			(start 1.1049 0.724916)
			(end -1.1049 0.724916)
			(stroke
				(width 0.1)
				(type default)
			)
			(layer "B.Fab")
		)
		(fp_line
			(start -1.1049 -0.724916)
			(end 1.1049 -0.724916)
			(stroke
				(width 0.1)
				(type default)
			)
			(layer "B.Fab")
		)
		(fp_line
			(start 1.1049 -0.724916)
			(end 1.1049 0.724916)
			(stroke
				(width 0.1)
				(type default)
			)
			(layer "B.Fab")
		)
		(pad "1" smd rect
			(at 0.889 0 270)
			(size 1.016 1.27)
			(layers "B.Cu" "B.Mask" "B.Paste")
			(net "SW_P12V_PVCCIN_CPU0_FLT")
		)
		(pad "2" smd rect
			(at -0.889 0 270)
			(size 1.016 1.27)
			(layers "B.Cu" "B.Mask" "B.Paste")
			(net "GND")
		)
	)
)
